# T6G (Grand Teton) — schematic parts with pin connectivity, parts 2608–2608 of 8303; source: Cadence DE-HDL packaged netlist (pstxprt.dat, pstxnet.dat, pstchip.dat)

J28  SCONN288_DDR506112002KQ  IO  pkg DDR288S_1-1VXC  page 100
  1  VIN_BULK0  POWER  = P12V_MEM_CPU1
  2  RFU0  TRI  = NC
  3  VIN_MGMT  POWER  = P3V3_AUX
  4  HSCL  IN  = I3C_SPD_DDRC_CPU1_SCL
  5  HSDA  BI  = I3C_SPD_DDRC_CPU1_SDA
  6  VSS0  POWER  = GND
  7  DQ0_A  BI  = M_C_CPU1_SA_DQ<0>
  8  VSS1  POWER  = GND
  9  DQ1_A  BI  = M_C_CPU1_SA_DQ<1>
  10  VSS2  POWER  = GND
  11  DQS0_A_T  BI  = M_C_CPU1_SA_DQS_DP<0>
  12  DQS0_A_C  BI  = M_C_CPU1_SA_DQS_DN<0>
  13  VSS3  POWER  = GND
  14  DQ4_A  BI  = M_C_CPU1_SA_DQ<4>
  15  VSS4  POWER  = GND
  16  DQ5_A  BI  = M_C_CPU1_SA_DQ<5>
  17  VSS5  POWER  = GND
  18  DQ8_A  BI  = M_C_CPU1_SA_DQ<8>
  19  VSS6  POWER  = GND
  20  DQ9_A  BI  = M_C_CPU1_SA_DQ<9>
  21  VSS7  POWER  = GND
  22  DQS1_A_T  BI  = M_C_CPU1_SA_DQS_DP<1>
  23  DQS1_A_C  BI  = M_C_CPU1_SA_DQS_DN<1>
  24  VSS8  POWER  = GND
  25  DQ12_A  BI  = M_C_CPU1_SA_DQ<12>
  26  VSS9  POWER  = GND
  27  DQ13_A  BI  = M_C_CPU1_SA_DQ<13>
  28  VSS10  POWER  = GND
  29  DQ16_A  BI  = M_C_CPU1_SA_DQ<16>
  30  VSS11  POWER  = GND
  31  DQ17_A  BI  = M_C_CPU1_SA_DQ<17>
  32  VSS12  POWER  = GND
  33  DQS2_A_T  BI  = M_C_CPU1_SA_DQS_DP<2>
  34  DQS2_A_C  BI  = M_C_CPU1_SA_DQS_DN<2>
  35  VSS13  POWER  = GND
  36  DQ20_A  BI  = M_C_CPU1_SA_DQ<20>
  37  VSS14  POWER  = GND
  38  DQ21_A  BI  = M_C_CPU1_SA_DQ<21>
  39  VSS15  POWER  = GND
  40  DQ24_A  BI  = M_C_CPU1_SA_DQ<24>
  41  VSS16  POWER  = GND
  42  DQ25_A  BI  = M_C_CPU1_SA_DQ<25>
  43  VSS17  POWER  = GND
  44  DQS3_A_T  BI  = M_C_CPU1_SA_DQS_DP<3>
  45  DQS3_A_C  BI  = M_C_CPU1_SA_DQS_DN<3>
  46  VSS18  POWER  = GND
  47  DQ28_A  BI  = M_C_CPU1_SA_DQ<28>
  48  VSS19  POWER  = GND
  49  DQ29_A  BI  = M_C_CPU1_SA_DQ<29>
  50  VSS20  POWER  = GND
  51  CB0_A  BI  = M_C_CPU1_SA_CB<0>
  52  VSS21  POWER  = GND
  53  CB1_A  BI  = M_C_CPU1_SA_CB<1>
  54  VSS22  POWER  = GND
  55  DQS4_A_T  BI  = M_C_CPU1_SA_DQS_DP<4>
  56  DQS4_A_C  BI  = M_C_CPU1_SA_DQS_DN<4>
  57  VSS23  POWER  = GND
  58  CB4_A  BI  = M_C_CPU1_SA_CB<4>
  59  VSS24  POWER  = GND
  60  CB5_A  BI  = M_C_CPU1_SA_CB<5>
  61  VSS25  POWER  = GND
  62  ALERT_N  OUT  = M_C_CPU1_ALERT_N
  63  VSS26  POWER  = GND
  64  CS0_A_N  IN  = M_C_CPU1_SA_CS_N<0>
  65  VSS27  POWER  = GND
  66  CA0_A  IN  = M_C_CPU1_SA_CA<0>
  67  VSS28  POWER  = GND
  68  CA2_A  IN  = M_C_CPU1_SA_CA<2>
  69  VSS29  POWER  = GND
  70  CA4_A  IN  = M_C_CPU1_SA_CA<4>
  71  VSS30  POWER  = GND
  72  CA6_A  IN  = M_C_CPU1_SA_CA<6>
  73  VSS31  POWER  = GND
  74  PAR_A  IN  = M_C_CPU1_SA_PAR
  75  VSS32  POWER  = GND
  76  CA0_B  IN  = M_C_CPU1_SB_CA<0>
  77  VSS33  POWER  = GND
  78  CA2_B  IN  = M_C_CPU1_SB_CA<2>
  79  VSS34  POWER  = GND
  80  CA4_B  IN  = M_C_CPU1_SB_CA<4>
  81  VSS35  POWER  = GND
  82  CA6_B  IN  = M_C_CPU1_SB_CA<6>
  83  VSS36  POWER  = GND
  84  CS0_B_N  IN  = M_C_CPU1_SB_CS_N<0>
  85  VSS37  POWER  = GND
  86  \lbd||rsp_a_n\  OUT  = M_C_CPU1_SA_RSP<0>
  87  \lbs||rsp_b_n\  OUT  = M_C_CPU1_SB_RSP<0>
  88  VSS38  POWER  = GND
  89  CB4_B  BI  = M_C_CPU1_SB_CB<4>
  90  VSS39  POWER  = GND
  91  CB5_B  BI  = M_C_CPU1_SB_CB<5>
  92  VSS40  POWER  = GND
  93  \dqs9_b_t||tdqs9_b_t||dbi4_b_n\  BI  = M_C_CPU1_SB_DQS_DP<9>
  94  \dqs9_b_c||tdqs9_b_c\  BI  = M_C_CPU1_SB_DQS_DN<9>
  95  VSS41  POWER  = GND
  96  CB0_B  BI  = M_C_CPU1_SB_CB<0>
  97  VSS42  POWER  = GND
  98  CB1_B  BI  = M_C_CPU1_SB_CB<1>
  99  VSS43  POWER  = GND
  100  DQ0_B  BI  = M_C_CPU1_SB_DQ<0>
  101  VSS44  POWER  = GND
  102  DQ1_B  BI  = M_C_CPU1_SB_DQ<1>
  103  VSS45  POWER  = GND
  104  DQS0_B_T  BI  = M_C_CPU1_SB_DQS_DP<0>
  105  DQS0_B_C  BI  = M_C_CPU1_SB_DQS_DN<0>
  106  VSS46  POWER  = GND
  107  DQ4_B  BI  = M_C_CPU1_SB_DQ<4>
  108  VSS47  POWER  = GND
  109  DQ5_B  BI  = M_C_CPU1_SB_DQ<5>
  110  VSS48  POWER  = GND
  111  DQ8_B  BI  = M_C_CPU1_SB_DQ<8>
  112  VSS49  POWER  = GND
  113  DQ9_B  BI  = M_C_CPU1_SB_DQ<9>
  114  VSS50  POWER  = GND
  115  DQS1_B_T  BI  = M_C_CPU1_SB_DQS_DP<1>
  116  DQS1_B_C  BI  = M_C_CPU1_SB_DQS_DN<1>
  117  VSS51  POWER  = GND
  118  DQ12_B  BI  = M_C_CPU1_SB_DQ<12>
  119  VSS52  POWER  = GND
  120  DQ13_B  BI  = M_C_CPU1_SB_DQ<13>
  121  VSS53  POWER  = GND
  122  DQ16_B  BI  = M_C_CPU1_SB_DQ<16>
  123  VSS54  POWER  = GND
  124  DQ17_B  BI  = M_C_CPU1_SB_DQ<17>
  125  VSS55  POWER  = GND
  126  DQS2_B_T  BI  = M_C_CPU1_SB_DQS_DP<2>
  127  DQS2_B_C  BI  = M_C_CPU1_SB_DQS_DN<2>
  128  VSS56  POWER  = GND
  129  DQ20_B  BI  = M_C_CPU1_SB_DQ<20>
  130  VSS57  POWER  = GND
  131  DQ21_B  BI  = M_C_CPU1_SB_DQ<21>
  132  VSS58  POWER  = GND
  133  DQ24_B  BI  = M_C_CPU1_SB_DQ<24>
  134  VSS59  POWER  = GND
  135  DQ25_B  BI  = M_C_CPU1_SB_DQ<25>
  136  VSS60  POWER  = GND
  137  DQS3_B_T  BI  = M_C_CPU1_SB_DQS_DP<3>
  138  DQS3_B_C  BI  = M_C_CPU1_SB_DQS_DN<3>
  139  VSS61  POWER  = GND
  140  DQ28_B  BI  = M_C_CPU1_SB_DQ<28>
  141  VSS62  POWER  = GND
  142  DQ29_B  BI  = M_C_CPU1_SB_DQ<29>
  143  VSS63  POWER  = GND
  144  RFU1  TRI  = NC
  145  VIN_BULK1  POWER  = P12V_MEM_CPU1
  146  VIN_BULK2  POWER  = P12V_MEM_CPU1
  147  \pwr_good||fail_n\  BI  = PWRGD_CHC_CPU1_DIMM
  148  HAS  IN  = PD_CHC_CPU1_DIMM_SAA
  149  RFU2  TRI  = NC
  150  RFU3  TRI  = NC
  151  VSS64  POWER  = GND
  152  DQ2_A  BI  = M_C_CPU1_SA_DQ<2>
  153  VSS65  POWER  = GND
  154  DQ3_A  BI  = M_C_CPU1_SA_DQ<3>
  155  VSS66  POWER  = GND
  156  \dqs5_a_c||tdqs5_a_c||dqs5_a_t||tdqs5_a_t\  BI  = M_C_CPU1_SA_DQS_DN<5>
  157  \dqs5_a_t||tdqs5_a_t\  BI  = M_C_CPU1_SA_DQS_DP<5>
  158  VSS67  POWER  = GND
  159  DQ6_A  BI  = M_C_CPU1_SA_DQ<6>
  160  VSS68  POWER  = GND
  161  DQ7_A  BI  = M_C_CPU1_SA_DQ<7>
  162  VSS69  POWER  = GND
  163  DQ10_A  BI  = M_C_CPU1_SA_DQ<10>
  164  VSS70  POWER  = GND
  165  DQ11_A  BI  = M_C_CPU1_SA_DQ<11>
  166  VSS71  POWER  = GND
  167  \dqs6_a_c||tdqs6_a_c||dqs6_a_t||tdqs6_a_t\  BI  = M_C_CPU1_SA_DQS_DN<6>
  168  \dqs6_a_t||tdqs6_a_t\  BI  = M_C_CPU1_SA_DQS_DP<6>
  169  VSS72  POWER  = GND
  170  DQ14_A  BI  = M_C_CPU1_SA_DQ<14>
  171  VSS73  POWER  = GND
  172  DQ15_A  BI  = M_C_CPU1_SA_DQ<15>
  173  VSS74  POWER  = GND
  174  DQ18_A  BI  = M_C_CPU1_SA_DQ<18>
  175  VSS75  POWER  = GND
  176  DQ19_A  BI  = M_C_CPU1_SA_DQ<19>
  177  VSS76  POWER  = GND
  178  \dqs7_a_c||tdqs7_a_c\  BI  = M_C_CPU1_SA_DQS_DN<7>
  179  \dqs7_a_t||tdqs7_a_t\  BI  = M_C_CPU1_SA_DQS_DP<7>
  180  VSS77  POWER  = GND
  181  DQ22_A  BI  = M_C_CPU1_SA_DQ<22>
  182  VSS78  POWER  = GND
  183  DQ23_A  BI  = M_C_CPU1_SA_DQ<23>
  184  VSS79  POWER  = GND
  185  DQ26_A  BI  = M_C_CPU1_SA_DQ<26>
  186  VSS80  POWER  = GND
  187  DQ27_A  BI  = M_C_CPU1_SA_DQ<27>
  188  VSS81  POWER  = GND
  189  \dqs8_a_c||tdqs8_a_c\  BI  = M_C_CPU1_SA_DQS_DN<8>
  190  \dqs8_a_t||tdqs8_a_t\  BI  = M_C_CPU1_SA_DQS_DP<8>
  191  VSS82  POWER  = GND
  192  DQ30_A  BI  = M_C_CPU1_SA_DQ<30>
  193  VSS83  POWER  = GND
  194  DQ31_A  BI  = M_C_CPU1_SA_DQ<31>
  195  VSS84  POWER  = GND
  196  CB2_A  BI  = M_C_CPU1_SA_CB<2>
  197  VSS85  POWER  = GND
  198  CB3_A  BI  = M_C_CPU1_SA_CB<3>
  199  VSS86  POWER  = GND
  200  \dqs9_a_c||tdqs9_a_c\  BI  = M_C_CPU1_SA_DQS_DN<9>
  201  \dqs9_a_t||tdqs9_a_t\  BI  = M_C_CPU1_SA_DQS_DP<9>
  202  VSS87  POWER  = GND
  203  CB6_A  BI  = M_C_CPU1_SA_CB<6>
  204  VSS88  POWER  = GND
  205  CB7_A  BI  = M_C_CPU1_SA_CB<7>
  206  VSS89  POWER  = GND
  207  RESET_N  IN  = M_C_CPU1_RESET_N
  208  VSS90  POWER  = GND
  209  CS1_A_N  IN  = M_C_CPU1_SA_CS_N<1>
  210  VSS91  POWER  = GND
  211  CA1_A  IN  = M_C_CPU1_SA_CA<1>
  212  VSS92  POWER  = GND
  213  CA3_A  IN  = M_C_CPU1_SA_CA<3>
  214  VSS93  POWER  = GND
  215  CA5_A  IN  = M_C_CPU1_SA_CA<5>
  216  VSS94  POWER  = GND
  217  CK_T  IN  = M_C_CPU1_CLK_DP<0>
  218  CK_C  IN  = M_C_CPU1_CLK_DN<0>
  219  VSS95  POWER  = GND
  220  RFU4  TRI  = NC
  221  CA1_B  IN  = M_C_CPU1_SB_CA<1>
  222  VSS96  POWER  = GND
  223  CA3_B  IN  = M_C_CPU1_SB_CA<3>
  224  VSS97  POWER  = GND
  225  CA5_B  IN  = M_C_CPU1_SB_CA<5>
  226  VSS98  POWER  = GND
  227  PAR_B  IN  = M_C_CPU1_SB_PAR
  228  VSS99  POWER  = GND
  229  CS1_B_N  IN  = M_C_CPU1_SB_CS_N<1>
  230  VSS100  POWER  = GND
  231  RFU5  TRI  = NC
  232  RFU6  TRI  = NC
  233  VSS101  POWER  = GND
  234  CB6_B  BI  = M_C_CPU1_SB_CB<6>
  235  VSS102  POWER  = GND
  236  CB7_B  BI  = M_C_CPU1_SB_CB<7>
  237  VSS103  POWER  = GND
  238  DQS4_B_C  BI  = M_C_CPU1_SB_DQS_DN<4>
  239  DQS4_B_T  BI  = M_C_CPU1_SB_DQS_DP<4>
  240  VSS104  POWER  = GND
  241  CB2_B  BI  = M_C_CPU1_SB_CB<2>
  242  VSS105  POWER  = GND
  243  CB3_B  BI  = M_C_CPU1_SB_CB<3>
  244  VSS106  POWER  = GND
  245  DQ2_B  BI  = M_C_CPU1_SB_DQ<2>
  246  VSS107  POWER  = GND
  247  DQ3_B  BI  = M_C_CPU1_SB_DQ<3>
  248  VSS108  POWER  = GND
  249  \dqs5_b_c||tdqs5_b_c\  BI  = M_C_CPU1_SB_DQS_DN<5>
  250  \dqs5_b_t||tdqs5_b_t\  BI  = M_C_CPU1_SB_DQS_DP<5>
  251  VSS109  POWER  = GND
  252  DQ6_B  BI  = M_C_CPU1_SB_DQ<6>
  253  VSS110  POWER  = GND
  254  DQ7_B  BI  = M_C_CPU1_SB_DQ<7>
  255  VSS111  POWER  = GND
  256  DQ10_B  BI  = M_C_CPU1_SB_DQ<10>
  257  VSS112  POWER  = GND
  258  DQ11_B  BI  = M_C_CPU1_SB_DQ<11>
  259  VSS113  POWER  = GND
  260  \dqs6_b_c||tdqs6_b_c\  BI  = M_C_CPU1_SB_DQS_DN<6>
  261  \dqs6_b_t||tdqs6_b_t\  BI  = M_C_CPU1_SB_DQS_DP<6>
  262  VSS114  POWER  = GND
  263  DQ14_B  BI  = M_C_CPU1_SB_DQ<14>
  264  VSS115  POWER  = GND
  265  DQ15_B  BI  = M_C_CPU1_SB_DQ<15>
  266  VSS116  POWER  = GND
  267  DQ18_B  BI  = M_C_CPU1_SB_DQ<18>
  268  VSS117  POWER  = GND
  269  DQ19_B  BI  = M_C_CPU1_SB_DQ<19>
  270  VSS118  POWER  = GND
  271  \dqs7_b_c||tdqs7_b_c\  BI  = M_C_CPU1_SB_DQS_DN<7>
  272  \dqs7_b_t||tdqs7_b_t\  BI  = M_C_CPU1_SB_DQS_DP<7>
  273  VSS119  POWER  = GND
  274  DQ22_B  BI  = M_C_CPU1_SB_DQ<22>
  275  VSS120  POWER  = GND
  276  DQ23_B  BI  = M_C_CPU1_SB_DQ<23>
  277  VSS121  POWER  = GND
  278  DQ26_B  BI  = M_C_CPU1_SB_DQ<26>
  279  VSS122  POWER  = GND
  280  DQ27_B  BI  = M_C_CPU1_SB_DQ<27>
  281  VSS123  POWER  = GND
  282  \dqs8_b_c||tdqs8_b_c\  BI  = M_C_CPU1_SB_DQS_DN<8>
  283  \dqs8_b_t||tdqs8_b_t\  BI  = M_C_CPU1_SB_DQS_DP<8>
  284  VSS124  POWER  = GND
  285  DQ30_B  BI  = M_C_CPU1_SB_DQ<30>
  286  VSS125  POWER  = GND
  287  DQ31_B  BI  = M_C_CPU1_SB_DQ<31>
  288  VSS126  POWER  = GND
  G1  G1  POWER  = GND
  G2  G2  POWER  = GND
  G3  G3  POWER  = GND
